(kicad_pcb
	(version 20260206)
	(generator "pcbnew")
	(generator_version "10.0")
	(general
		(thickness 1.6)
		(legacy_teardrops no)
	)
	(paper "A4")
	(title_block
		(title "Bryce Canyon_R.DPB_16317-1_OCP.brd")
		(comment 1 "Bryce Canyon / footprint 274 of 2099 (SAS1), pads 1-70 of 342")
	)
	(layers
		(0 "F.Cu" signal "TOP")
		(4 "In1.Cu" signal "L2GND")
		(6 "In2.Cu" signal "L3")
		(8 "In3.Cu" signal "L4VCC")
		(10 "In4.Cu" signal "L5VCC")
		(12 "In5.Cu" signal "L6")
		(14 "In6.Cu" signal "L7GND")
		(2 "B.Cu" signal "BOTTOM")
		(9 "F.Adhes" user "F.Adhesive")
		(11 "B.Adhes" user "B.Adhesive")
		(13 "F.Paste" user "Package Geometry/Pastemask Top")
		(15 "B.Paste" user "Package Geometry/Pastemask Bottom")
		(5 "F.SilkS" user "Ref Des/Silkscreen Top")
		(7 "B.SilkS" user "Ref Des/Silkscreen Bottom")
		(1 "F.Mask" user "Board Geometry/Soldermask Top")
		(3 "B.Mask" user "Board Geometry/Soldermask Bottom")
		(17 "Dwgs.User" user "User.Drawings")
		(19 "Cmts.User" user "User.Comments")
		(21 "Eco1.User" user "User.Eco1")
		(23 "Eco2.User" user "User.Eco2")
		(25 "Edge.Cuts" user "Board Geometry/Outline")
		(27 "Margin" user)
		(31 "F.CrtYd" user "Package Geometry/Place Bound Top")
		(29 "B.CrtYd" user "Package Geometry/Place Bound Bottom")
		(35 "F.Fab" user "Ref Des/Assembly Top")
		(33 "B.Fab" user "Ref Des/Assembly Bottom")
	)
	(footprint ""
		(layer "F.Cu")
		(at 287.83661 -238.694468 -90)
		(property "Reference" "SAS1"
			(at 0 0 270)
			(layer "F.SilkS")
			(hide yes)
			(effects
				(font
					(size 1.27 1.27)
				)
			)
		)
		(property "Value" "AMP-CONN342-10R-2-GP"
			(at 20.955 -16.7386 270)
			(unlocked yes)
			(layer "F.Fab")
			(hide yes)
			(effects
				(font
					(size 1.016 1.016)
					(thickness 0.1524)
				)
			)
		)
		(property "Device Type" "PREFIT-342P-668151H483"
			(at 20.955 -18.2626 270)
			(unlocked yes)
			(layer "F.Fab")
			(hide yes)
			(effects
				(font
					(size 1.016 1.016)
					(thickness 0.1524)
				)
			)
		)
		(duplicate_pad_numbers_are_jumpers no)
		(pad "A1" thru_hole circle
			(at 0 0 270)
			(size 0.762 0.762)
			(drill 0.359918)
			(layers "*.Cu" "*.Mask")
			(remove_unused_layers no)
			(net "PHY_DRV_B_TO_SCC_B_5_DN")
			(clearance 0.1651)
			(thermal_gap 0.1651)
		)
		(pad "A2" thru_hole circle
			(at 1.800098 0.999998 270)
			(size 0.762 0.762)
			(drill 0.359918)
			(layers "*.Cu" "*.Mask")
			(remove_unused_layers no)
			(net "PHY_DRV_B_TO_SCC_B_4_DN")
			(clearance 0.1651)
			(thermal_gap 0.1651)
		)
		(pad "A3" thru_hole circle
			(at 3.599942 0 270)
			(size 0.762 0.762)
			(drill 0.359918)
			(layers "*.Cu" "*.Mask")
			(remove_unused_layers no)
			(net "PHY_DRV_B_TO_SCC_B_3_DN")
			(clearance 0.1651)
			(thermal_gap 0.1651)
		)
		(pad "A4" thru_hole circle
			(at 5.40004 0.999998 270)
			(size 0.762 0.762)
			(drill 0.359918)
			(layers "*.Cu" "*.Mask")
			(remove_unused_layers no)
			(net "PHY_DRV_B_TO_SCC_B_2_DN")
			(clearance 0.1651)
			(thermal_gap 0.1651)
		)
		(pad "A5" thru_hole circle
			(at 7.199884 0 270)
			(size 0.762 0.762)
			(drill 0.359918)
			(layers "*.Cu" "*.Mask")
			(remove_unused_layers no)
			(net "PHY_DRV_B_TO_SCC_B_1_DN")
			(clearance 0.1651)
			(thermal_gap 0.1651)
		)
		(pad "A6" thru_hole circle
			(at 8.999982 0.999998 270)
			(size 0.762 0.762)
			(drill 0.359918)
			(layers "*.Cu" "*.Mask")
			(remove_unused_layers no)
			(net "PHY_DRV_B_TO_SCC_B_0_DN")
			(clearance 0.1651)
			(thermal_gap 0.1651)
		)
		(pad "A7" thru_hole circle
			(at 10.80008 0 270)
			(size 0.762 0.762)
			(drill 0.359918)
			(layers "*.Cu" "*.Mask")
			(remove_unused_layers no)
			(net "PHY_DRV_B_TO_SCC_B_6_DN")
			(clearance 0.1651)
			(thermal_gap 0.1651)
		)
		(pad "A8" thru_hole circle
			(at 12.599924 0.999998 270)
			(size 0.762 0.762)
			(drill 0.359918)
			(layers "*.Cu" "*.Mask")
			(remove_unused_layers no)
			(net "PHY_DRV_B_TO_SCC_B_7_DN")
			(clearance 0.1651)
			(thermal_gap 0.1651)
		)
		(pad "A9" thru_hole circle
			(at 14.400022 0 270)
			(size 0.762 0.762)
			(drill 0.359918)
			(layers "*.Cu" "*.Mask")
			(remove_unused_layers no)
			(net "PHY_DRV_B_TO_SCC_B_8_DN")
			(clearance 0.1651)
			(thermal_gap 0.1651)
		)
		(pad "A10" thru_hole circle
			(at 16.20012 0.999998 270)
			(size 0.762 0.762)
			(drill 0.359918)
			(layers "*.Cu" "*.Mask")
			(remove_unused_layers no)
			(net "PHY_DRV_B_TO_SCC_B_9_DN")
			(clearance 0.1651)
			(thermal_gap 0.1651)
		)
		(pad "A11" thru_hole circle
			(at 17.999964 0 270)
			(size 0.762 0.762)
			(drill 0.359918)
			(layers "*.Cu" "*.Mask")
			(remove_unused_layers no)
			(net "PHY_DRV_B_TO_SCC_B_10_DN")
			(clearance 0.1651)
			(thermal_gap 0.1651)
		)
		(pad "A12" thru_hole circle
			(at 19.800062 0.999998 270)
			(size 0.762 0.762)
			(drill 0.359918)
			(layers "*.Cu" "*.Mask")
			(remove_unused_layers no)
			(net "PHY_DRV_B_TO_SCC_B_11_DN")
			(clearance 0.1651)
			(thermal_gap 0.1651)
		)
		(pad "A13" thru_hole circle
			(at 21.599906 0 270)
			(size 0.762 0.762)
			(drill 0.359918)
			(layers "*.Cu" "*.Mask")
			(remove_unused_layers no)
			(net "PHY_DRV_B_TO_SCC_B_12_DN")
			(clearance 0.1651)
			(thermal_gap 0.1651)
		)
		(pad "A14" thru_hole circle
			(at 23.400004 0.999998 270)
			(size 0.762 0.762)
			(drill 0.359918)
			(layers "*.Cu" "*.Mask")
			(remove_unused_layers no)
			(net "PHY_DRV_B_TO_SCC_B_13_DN")
			(clearance 0.1651)
			(thermal_gap 0.1651)
		)
		(pad "A15" thru_hole circle
			(at 25.200102 0 270)
			(size 0.762 0.762)
			(drill 0.359918)
			(layers "*.Cu" "*.Mask")
			(remove_unused_layers no)
			(net "PHY_DRV_B_TO_SCC_B_14_DN")
			(clearance 0.1651)
			(thermal_gap 0.1651)
		)
		(pad "A16" thru_hole circle
			(at 26.999946 0.999998 270)
			(size 0.762 0.762)
			(drill 0.359918)
			(layers "*.Cu" "*.Mask")
			(remove_unused_layers no)
			(net "PHY_DRV_B_TO_SCC_B_15_DN")
			(clearance 0.1651)
			(thermal_gap 0.1651)
		)
		(pad "A17" thru_hole circle
			(at 28.800044 0 270)
			(size 0.762 0.762)
			(drill 0.359918)
			(layers "*.Cu" "*.Mask")
			(remove_unused_layers no)
			(net "PHY_DRV_B_TO_SCC_B_16_DN")
			(clearance 0.1651)
			(thermal_gap 0.1651)
		)
		(pad "A18" thru_hole circle
			(at 30.599888 0.999998 270)
			(size 0.762 0.762)
			(drill 0.359918)
			(layers "*.Cu" "*.Mask")
			(remove_unused_layers no)
			(net "PHY_DRV_B_TO_SCC_B_17_DN")
			(clearance 0.1651)
			(thermal_gap 0.1651)
		)
		(pad "A19" thru_hole circle
			(at 32.399986 0 270)
			(size 0.762 0.762)
			(drill 0.359918)
			(layers "*.Cu" "*.Mask")
			(remove_unused_layers no)
			(net "PHY_DRV_B_TO_SCC_B_23_DN")
			(clearance 0.1651)
			(thermal_gap 0.1651)
		)
		(pad "A20" thru_hole circle
			(at 34.200084 0.999998 270)
			(size 0.762 0.762)
			(drill 0.359918)
			(layers "*.Cu" "*.Mask")
			(remove_unused_layers no)
			(net "PHY_DRV_B_TO_SCC_B_22_DN")
			(clearance 0.1651)
			(thermal_gap 0.1651)
		)
		(pad "A21" thru_hole circle
			(at 35.999928 0 270)
			(size 0.762 0.762)
			(drill 0.359918)
			(layers "*.Cu" "*.Mask")
			(remove_unused_layers no)
			(net "PHY_DRV_B_TO_SCC_B_21_DN")
			(clearance 0.1651)
			(thermal_gap 0.1651)
		)
		(pad "A22" thru_hole circle
			(at 37.800026 0.999998 270)
			(size 0.762 0.762)
			(drill 0.359918)
			(layers "*.Cu" "*.Mask")
			(remove_unused_layers no)
			(net "PHY_DRV_B_TO_SCC_B_20_DN")
			(clearance 0.1651)
			(thermal_gap 0.1651)
		)
		(pad "A23" thru_hole circle
			(at 39.600124 0 270)
			(size 0.762 0.762)
			(drill 0.359918)
			(layers "*.Cu" "*.Mask")
			(remove_unused_layers no)
			(net "PHY_DRV_B_TO_SCC_B_19_DN")
			(clearance 0.1651)
			(thermal_gap 0.1651)
		)
		(pad "A24" thru_hole circle
			(at 41.399968 0.999998 270)
			(size 0.762 0.762)
			(drill 0.359918)
			(layers "*.Cu" "*.Mask")
			(remove_unused_layers no)
			(net "PHY_DRV_B_TO_SCC_B_18_DN")
			(clearance 0.1651)
			(thermal_gap 0.1651)
		)
		(pad "A25" thru_hole circle
			(at 43.200066 0 270)
			(size 0.762 0.762)
			(drill 0.359918)
			(layers "*.Cu" "*.Mask")
			(remove_unused_layers no)
			(net "PHY_DRV_B_TO_SCC_B_24_DN")
			(clearance 0.1651)
			(thermal_gap 0.1651)
		)
		(pad "A26" thru_hole circle
			(at 44.99991 0.999998 270)
			(size 0.762 0.762)
			(drill 0.359918)
			(layers "*.Cu" "*.Mask")
			(remove_unused_layers no)
			(net "PHY_DRV_B_TO_SCC_B_25_DN")
			(clearance 0.1651)
			(thermal_gap 0.1651)
		)
		(pad "A27" thru_hole circle
			(at 46.800008 0 270)
			(size 0.762 0.762)
			(drill 0.359918)
			(layers "*.Cu" "*.Mask")
			(remove_unused_layers no)
			(net "PHY_DRV_B_TO_SCC_B_26_DN")
			(clearance 0.1651)
			(thermal_gap 0.1651)
		)
		(pad "A28" thru_hole circle
			(at 48.600106 0.999998 270)
			(size 0.762 0.762)
			(drill 0.359918)
			(layers "*.Cu" "*.Mask")
			(remove_unused_layers no)
			(net "PHY_DRV_B_TO_SCC_B_27_DN")
			(clearance 0.1651)
			(thermal_gap 0.1651)
		)
		(pad "A29" thru_hole circle
			(at 50.39995 0 270)
			(size 0.762 0.762)
			(drill 0.359918)
			(layers "*.Cu" "*.Mask")
			(remove_unused_layers no)
			(net "PHY_DRV_B_TO_SCC_B_28_DN")
			(clearance 0.1651)
			(thermal_gap 0.1651)
		)
		(pad "A30" thru_hole circle
			(at 52.200048 0.999998 270)
			(size 0.762 0.762)
			(drill 0.359918)
			(layers "*.Cu" "*.Mask")
			(remove_unused_layers no)
			(net "PHY_DRV_B_TO_SCC_B_29_DN")
			(clearance 0.1651)
			(thermal_gap 0.1651)
		)
		(pad "A31" thru_hole circle
			(at 53.999892 0 270)
			(size 0.762 0.762)
			(drill 0.359918)
			(layers "*.Cu" "*.Mask")
			(remove_unused_layers no)
			(net "PHY_DRV_B_TO_SCC_B_35_DN")
			(clearance 0.1651)
			(thermal_gap 0.1651)
		)
		(pad "A32" thru_hole circle
			(at 55.79999 0.999998 270)
			(size 0.762 0.762)
			(drill 0.359918)
			(layers "*.Cu" "*.Mask")
			(remove_unused_layers no)
			(net "PHY_DRV_B_TO_SCC_B_34_DN")
			(clearance 0.1651)
			(thermal_gap 0.1651)
		)
		(pad "A33" thru_hole circle
			(at 57.600088 0 270)
			(size 0.762 0.762)
			(drill 0.359918)
			(layers "*.Cu" "*.Mask")
			(remove_unused_layers no)
			(net "PHY_DRV_B_TO_SCC_B_33_DN")
			(clearance 0.1651)
			(thermal_gap 0.1651)
		)
		(pad "A34" thru_hole circle
			(at 59.399932 0.999998 270)
			(size 0.762 0.762)
			(drill 0.359918)
			(layers "*.Cu" "*.Mask")
			(remove_unused_layers no)
			(net "PHY_DRV_B_TO_SCC_B_32_DN")
			(clearance 0.1651)
			(thermal_gap 0.1651)
		)
		(pad "A35" thru_hole circle
			(at 61.20003 0 270)
			(size 0.762 0.762)
			(drill 0.359918)
			(layers "*.Cu" "*.Mask")
			(remove_unused_layers no)
			(net "PHY_DRV_B_TO_SCC_B_31_DN")
			(clearance 0.1651)
			(thermal_gap 0.1651)
		)
		(pad "A36" thru_hole circle
			(at 62.999874 0.999998 270)
			(size 0.762 0.762)
			(drill 0.359918)
			(layers "*.Cu" "*.Mask")
			(remove_unused_layers no)
			(net "PHY_DRV_B_TO_SCC_B_30_DN")
			(clearance 0.1651)
			(thermal_gap 0.1651)
		)
		(pad "B1" thru_hole circle
			(at 0 1.400048 270)
			(size 0.762 0.762)
			(drill 0.359918)
			(layers "*.Cu" "*.Mask")
			(remove_unused_layers no)
			(net "PHY_DRV_B_TO_SCC_B_5_DP")
			(clearance 0.1651)
			(thermal_gap 0.1651)
		)
		(pad "B2" thru_hole circle
			(at 1.800098 2.400046 270)
			(size 0.762 0.762)
			(drill 0.359918)
			(layers "*.Cu" "*.Mask")
			(remove_unused_layers no)
			(net "PHY_DRV_B_TO_SCC_B_4_DP")
			(clearance 0.1651)
			(thermal_gap 0.1651)
		)
		(pad "B3" thru_hole circle
			(at 3.599942 1.400048 270)
			(size 0.762 0.762)
			(drill 0.359918)
			(layers "*.Cu" "*.Mask")
			(remove_unused_layers no)
			(net "PHY_DRV_B_TO_SCC_B_3_DP")
			(clearance 0.1651)
			(thermal_gap 0.1651)
		)
		(pad "B4" thru_hole circle
			(at 5.40004 2.400046 270)
			(size 0.762 0.762)
			(drill 0.359918)
			(layers "*.Cu" "*.Mask")
			(remove_unused_layers no)
			(net "PHY_DRV_B_TO_SCC_B_2_DP")
			(clearance 0.1651)
			(thermal_gap 0.1651)
		)
		(pad "B5" thru_hole circle
			(at 7.199884 1.400048 270)
			(size 0.762 0.762)
			(drill 0.359918)
			(layers "*.Cu" "*.Mask")
			(remove_unused_layers no)
			(net "PHY_DRV_B_TO_SCC_B_1_DP")
			(clearance 0.1651)
			(thermal_gap 0.1651)
		)
		(pad "B6" thru_hole circle
			(at 8.999982 2.400046 270)
			(size 0.762 0.762)
			(drill 0.359918)
			(layers "*.Cu" "*.Mask")
			(remove_unused_layers no)
			(net "PHY_DRV_B_TO_SCC_B_0_DP")
			(clearance 0.1651)
			(thermal_gap 0.1651)
		)
		(pad "B7" thru_hole circle
			(at 10.80008 1.400048 270)
			(size 0.762 0.762)
			(drill 0.359918)
			(layers "*.Cu" "*.Mask")
			(remove_unused_layers no)
			(net "PHY_DRV_B_TO_SCC_B_6_DP")
			(clearance 0.1651)
			(thermal_gap 0.1651)
		)
		(pad "B8" thru_hole circle
			(at 12.599924 2.400046 270)
			(size 0.762 0.762)
			(drill 0.359918)
			(layers "*.Cu" "*.Mask")
			(remove_unused_layers no)
			(net "PHY_DRV_B_TO_SCC_B_7_DP")
			(clearance 0.1651)
			(thermal_gap 0.1651)
		)
		(pad "B9" thru_hole circle
			(at 14.400022 1.400048 270)
			(size 0.762 0.762)
			(drill 0.359918)
			(layers "*.Cu" "*.Mask")
			(remove_unused_layers no)
			(net "PHY_DRV_B_TO_SCC_B_8_DP")
			(clearance 0.1651)
			(thermal_gap 0.1651)
		)
		(pad "B10" thru_hole circle
			(at 16.20012 2.400046 270)
			(size 0.762 0.762)
			(drill 0.359918)
			(layers "*.Cu" "*.Mask")
			(remove_unused_layers no)
			(net "PHY_DRV_B_TO_SCC_B_9_DP")
			(clearance 0.1651)
			(thermal_gap 0.1651)
		)
		(pad "B11" thru_hole circle
			(at 17.999964 1.400048 270)
			(size 0.762 0.762)
			(drill 0.359918)
			(layers "*.Cu" "*.Mask")
			(remove_unused_layers no)
			(net "PHY_DRV_B_TO_SCC_B_10_DP")
			(clearance 0.1651)
			(thermal_gap 0.1651)
		)
		(pad "B12" thru_hole circle
			(at 19.800062 2.400046 270)
			(size 0.762 0.762)
			(drill 0.359918)
			(layers "*.Cu" "*.Mask")
			(remove_unused_layers no)
			(net "PHY_DRV_B_TO_SCC_B_11_DP")
			(clearance 0.1651)
			(thermal_gap 0.1651)
		)
		(pad "B13" thru_hole circle
			(at 21.599906 1.400048 270)
			(size 0.762 0.762)
			(drill 0.359918)
			(layers "*.Cu" "*.Mask")
			(remove_unused_layers no)
			(net "PHY_DRV_B_TO_SCC_B_12_DP")
			(clearance 0.1651)
			(thermal_gap 0.1651)
		)
		(pad "B14" thru_hole circle
			(at 23.400004 2.400046 270)
			(size 0.762 0.762)
			(drill 0.359918)
			(layers "*.Cu" "*.Mask")
			(remove_unused_layers no)
			(net "PHY_DRV_B_TO_SCC_B_13_DP")
			(clearance 0.1651)
			(thermal_gap 0.1651)
		)
		(pad "B15" thru_hole circle
			(at 25.200102 1.400048 270)
			(size 0.762 0.762)
			(drill 0.359918)
			(layers "*.Cu" "*.Mask")
			(remove_unused_layers no)
			(net "PHY_DRV_B_TO_SCC_B_14_DP")
			(clearance 0.1651)
			(thermal_gap 0.1651)
		)
		(pad "B16" thru_hole circle
			(at 26.999946 2.400046 270)
			(size 0.762 0.762)
			(drill 0.359918)
			(layers "*.Cu" "*.Mask")
			(remove_unused_layers no)
			(net "PHY_DRV_B_TO_SCC_B_15_DP")
			(clearance 0.1651)
			(thermal_gap 0.1651)
		)
		(pad "B17" thru_hole circle
			(at 28.800044 1.400048 270)
			(size 0.762 0.762)
			(drill 0.359918)
			(layers "*.Cu" "*.Mask")
			(remove_unused_layers no)
			(net "PHY_DRV_B_TO_SCC_B_16_DP")
			(clearance 0.1651)
			(thermal_gap 0.1651)
		)
		(pad "B18" thru_hole circle
			(at 30.599888 2.400046 270)
			(size 0.762 0.762)
			(drill 0.359918)
			(layers "*.Cu" "*.Mask")
			(remove_unused_layers no)
			(net "PHY_DRV_B_TO_SCC_B_17_DP")
			(clearance 0.1651)
			(thermal_gap 0.1651)
		)
		(pad "B19" thru_hole circle
			(at 32.399986 1.400048 270)
			(size 0.762 0.762)
			(drill 0.359918)
			(layers "*.Cu" "*.Mask")
			(remove_unused_layers no)
			(net "PHY_DRV_B_TO_SCC_B_23_DP")
			(clearance 0.1651)
			(thermal_gap 0.1651)
		)
		(pad "B20" thru_hole circle
			(at 34.200084 2.400046 270)
			(size 0.762 0.762)
			(drill 0.359918)
			(layers "*.Cu" "*.Mask")
			(remove_unused_layers no)
			(net "PHY_DRV_B_TO_SCC_B_22_DP")
			(clearance 0.1651)
			(thermal_gap 0.1651)
		)
		(pad "B21" thru_hole circle
			(at 35.999928 1.400048 270)
			(size 0.762 0.762)
			(drill 0.359918)
			(layers "*.Cu" "*.Mask")
			(remove_unused_layers no)
			(net "PHY_DRV_B_TO_SCC_B_21_DP")
			(clearance 0.1651)
			(thermal_gap 0.1651)
		)
		(pad "B22" thru_hole circle
			(at 37.800026 2.400046 270)
			(size 0.762 0.762)
			(drill 0.359918)
			(layers "*.Cu" "*.Mask")
			(remove_unused_layers no)
			(net "PHY_DRV_B_TO_SCC_B_20_DP")
			(clearance 0.1651)
			(thermal_gap 0.1651)
		)
		(pad "B23" thru_hole circle
			(at 39.600124 1.400048 270)
			(size 0.762 0.762)
			(drill 0.359918)
			(layers "*.Cu" "*.Mask")
			(remove_unused_layers no)
			(net "PHY_DRV_B_TO_SCC_B_19_DP")
			(clearance 0.1651)
			(thermal_gap 0.1651)
		)
		(pad "B24" thru_hole circle
			(at 41.399968 2.400046 270)
			(size 0.762 0.762)
			(drill 0.359918)
			(layers "*.Cu" "*.Mask")
			(remove_unused_layers no)
			(net "PHY_DRV_B_TO_SCC_B_18_DP")
			(clearance 0.1651)
			(thermal_gap 0.1651)
		)
		(pad "B25" thru_hole circle
			(at 43.200066 1.400048 270)
			(size 0.762 0.762)
			(drill 0.359918)
			(layers "*.Cu" "*.Mask")
			(remove_unused_layers no)
			(net "PHY_DRV_B_TO_SCC_B_24_DP")
			(clearance 0.1651)
			(thermal_gap 0.1651)
		)
		(pad "B26" thru_hole circle
			(at 44.99991 2.400046 270)
			(size 0.762 0.762)
			(drill 0.359918)
			(layers "*.Cu" "*.Mask")
			(remove_unused_layers no)
			(net "PHY_DRV_B_TO_SCC_B_25_DP")
			(clearance 0.1651)
			(thermal_gap 0.1651)
		)
		(pad "B27" thru_hole circle
			(at 46.800008 1.400048 270)
			(size 0.762 0.762)
			(drill 0.359918)
			(layers "*.Cu" "*.Mask")
			(remove_unused_layers no)
			(net "PHY_DRV_B_TO_SCC_B_26_DP")
			(clearance 0.1651)
			(thermal_gap 0.1651)
		)
		(pad "B28" thru_hole circle
			(at 48.600106 2.400046 270)
			(size 0.762 0.762)
			(drill 0.359918)
			(layers "*.Cu" "*.Mask")
			(remove_unused_layers no)
			(net "PHY_DRV_B_TO_SCC_B_27_DP")
			(clearance 0.1651)
			(thermal_gap 0.1651)
		)
		(pad "B29" thru_hole circle
			(at 50.39995 1.400048 270)
			(size 0.762 0.762)
			(drill 0.359918)
			(layers "*.Cu" "*.Mask")
			(remove_unused_layers no)
			(net "PHY_DRV_B_TO_SCC_B_28_DP")
			(clearance 0.1651)
			(thermal_gap 0.1651)
		)
		(pad "B30" thru_hole circle
			(at 52.200048 2.400046 270)
			(size 0.762 0.762)
			(drill 0.359918)
			(layers "*.Cu" "*.Mask")
			(remove_unused_layers no)
			(net "PHY_DRV_B_TO_SCC_B_29_DP")
			(clearance 0.1651)
			(thermal_gap 0.1651)
		)
		(pad "B31" thru_hole circle
			(at 53.999892 1.400048 270)
			(size 0.762 0.762)
			(drill 0.359918)
			(layers "*.Cu" "*.Mask")
			(remove_unused_layers no)
			(net "PHY_DRV_B_TO_SCC_B_35_DP")
			(clearance 0.1651)
			(thermal_gap 0.1651)
		)
		(pad "B32" thru_hole circle
			(at 55.79999 2.400046 270)
			(size 0.762 0.762)
			(drill 0.359918)
			(layers "*.Cu" "*.Mask")
			(remove_unused_layers no)
			(net "PHY_DRV_B_TO_SCC_B_34_DP")
			(clearance 0.1651)
			(thermal_gap 0.1651)
		)
		(pad "B33" thru_hole circle
			(at 57.600088 1.400048 270)
			(size 0.762 0.762)
			(drill 0.359918)
			(layers "*.Cu" "*.Mask")
			(remove_unused_layers no)
			(net "PHY_DRV_B_TO_SCC_B_33_DP")
			(clearance 0.1651)
			(thermal_gap 0.1651)
		)
		(pad "B34" thru_hole circle
			(at 59.399932 2.400046 270)
			(size 0.762 0.762)
			(drill 0.359918)
			(layers "*.Cu" "*.Mask")
			(remove_unused_layers no)
			(net "PHY_DRV_B_TO_SCC_B_32_DP")
			(clearance 0.1651)
			(thermal_gap 0.1651)
		)
	)
)
